# T6G (Grand Teton) — schematic netlist excerpt (pin names and nets, part order shuffled) for the footprints in the layout excerpt that follows; sources: Cadence DE-HDL packaged netlist, KiCad conversion of 04192023_DAF0TMB3IC0_F0TG_MB_C_brd_V02_OCP.brd

C37  Q_CAP  0.1UF 25V 10% X7R  pkg 0402  page 257 : A = P12V_OCP_SFF_ISENSE_TIC ; B = GND
R2310  Q_RES  0 5% EMPTY  pkg 0402LF  page 159 : A = I3C_0_SPD_DDRAF_CPU0_R_SCL ; B = I3C_SPD_DDRAF_CPU0_BYPASS_SCL

(kicad_pcb
	(version 20260206)
	(generator "pcbnew")
	(generator_version "10.0")
	(general
		(thickness 1.6)
		(legacy_teardrops no)
	)
	(paper "A4")
	(title_block
		(title "04192023_DAF0TMB3IC0_F0TG_MB_C_brd_V02_OCP.brd")
		(comment 1 "Grand Teton / footprints 4759-4760 of 8354")
	)
	(layers
		(0 "F.Cu" signal "TOP")
		(4 "In1.Cu" signal "GND")
		(6 "In2.Cu" signal "IN1")
		(8 "In3.Cu" signal "GND1")
		(10 "In4.Cu" signal "IN2")
		(12 "In5.Cu" signal "GND2")
		(14 "In6.Cu" signal "IN3")
		(16 "In7.Cu" signal "GND3")
		(18 "In8.Cu" signal "VCC")
		(20 "In9.Cu" signal "VCC1")
		(22 "In10.Cu" signal "GND4")
		(24 "In11.Cu" signal "IN4")
		(26 "In12.Cu" signal "GND5")
		(28 "In13.Cu" signal "IN5")
		(30 "In14.Cu" signal "GND6")
		(32 "In15.Cu" signal "IN6")
		(34 "In16.Cu" signal "GND7")
		(2 "B.Cu" signal "BOTTOM")
		(9 "F.Adhes" user "F.Adhesive")
		(11 "B.Adhes" user "B.Adhesive")
		(13 "F.Paste" user "Package Geometry/Pastemask Top")
		(15 "B.Paste" user "Package Geometry/Pastemask Bottom")
		(5 "F.SilkS" user "Ref Des/Silkscreen Top")
		(7 "B.SilkS" user "Ref Des/Silkscreen Bottom")
		(1 "F.Mask" user "Board Geometry/Soldermask Top")
		(3 "B.Mask" user "Board Geometry/Soldermask Bottom")
		(17 "Dwgs.User" user "User.Drawings")
		(19 "Cmts.User" user "User.Comments")
		(21 "Eco1.User" user "User.Eco1")
		(23 "Eco2.User" user "User.Eco2")
		(25 "Edge.Cuts" user "Board Geometry/Outline")
		(27 "Margin" user)
		(31 "F.CrtYd" user "Package Geometry/Place Bound Top")
		(29 "B.CrtYd" user "Package Geometry/Place Bound Bottom")
		(35 "F.Fab" user "Ref Des/Assembly Top")
		(33 "B.Fab" user "Ref Des/Assembly Bottom")
	)
	(footprint ""
		(layer "F.Cu")
		(at 320.981324 -192.09766 -90)
		(property "Reference" "R2310"
			(at 0 0 270)
			(layer "F.SilkS")
			(hide yes)
			(effects
				(font
					(size 1.27 1.27)
				)
			)
		)
		(property "Value" ""
			(at 0 0 270)
			(layer "F.Fab")
			(effects
				(font
					(size 1.27 1.27)
				)
			)
		)
		(duplicate_pad_numbers_are_jumpers no)
		(fp_line
			(start -0.7874 0.4064)
			(end -0.7874 -0.4064)
			(stroke
				(width 0.1524)
				(type default)
			)
			(layer "F.SilkS")
		)
		(fp_line
			(start 0.7874 0.4064)
			(end -0.7874 0.4064)
			(stroke
				(width 0.1524)
				(type default)
			)
			(layer "F.SilkS")
		)
		(fp_line
			(start -0.7874 -0.4064)
			(end 0.7874 -0.4064)
			(stroke
				(width 0.1524)
				(type default)
			)
			(layer "F.SilkS")
		)
		(fp_line
			(start 0.7874 -0.4064)
			(end 0.7874 0.4064)
			(stroke
				(width 0.1524)
				(type default)
			)
			(layer "F.SilkS")
		)
		(fp_line
			(start -0.67945 0.3048)
			(end -0.67945 -0.305054)
			(stroke
				(width 0.1)
				(type default)
			)
			(layer "F.Fab")
		)
		(fp_line
			(start -0.12065 0.3048)
			(end -0.67945 0.3048)
			(stroke
				(width 0.1)
				(type default)
			)
			(layer "F.Fab")
		)
		(fp_line
			(start 0.120396 0.3048)
			(end 0.120396 0.2794)
			(stroke
				(width 0.1)
				(type default)
			)
			(layer "F.Fab")
		)
		(fp_line
			(start 0.67945 0.3048)
			(end 0.120396 0.3048)
			(stroke
				(width 0.1)
				(type default)
			)
			(layer "F.Fab")
		)
		(fp_line
			(start -0.12065 0.2794)
			(end -0.12065 0.3048)
			(stroke
				(width 0.1)
				(type default)
			)
			(layer "F.Fab")
		)
		(fp_line
			(start 0.120396 0.2794)
			(end -0.12065 0.2794)
			(stroke
				(width 0.1)
				(type default)
			)
			(layer "F.Fab")
		)
		(fp_line
			(start -0.12065 -0.2794)
			(end 0.12065 -0.2794)
			(stroke
				(width 0.1)
				(type default)
			)
			(layer "F.Fab")
		)
		(fp_line
			(start 0.12065 -0.2794)
			(end 0.12065 -0.3048)
			(stroke
				(width 0.1)
				(type default)
			)
			(layer "F.Fab")
		)
		(fp_line
			(start 0.12065 -0.3048)
			(end 0.67945 -0.3048)
			(stroke
				(width 0.1)
				(type default)
			)
			(layer "F.Fab")
		)
		(fp_line
			(start 0.67945 -0.3048)
			(end 0.67945 0.3048)
			(stroke
				(width 0.1)
				(type default)
			)
			(layer "F.Fab")
		)
		(fp_line
			(start -0.67945 -0.305054)
			(end -0.12065 -0.305054)
			(stroke
				(width 0.1)
				(type default)
			)
			(layer "F.Fab")
		)
		(fp_line
			(start -0.12065 -0.305054)
			(end -0.12065 -0.2794)
			(stroke
				(width 0.1)
				(type default)
			)
			(layer "F.Fab")
		)
		(pad "1" smd rect
			(at -0.40005 0 90)
			(size 0.4572 0.508)
			(layers "F.Cu" "F.Mask" "F.Paste")
			(net "I3C_0_SPD_DDRAF_CPU0_R_SCL")
		)
		(pad "2" smd rect
			(at 0.40005 0 90)
			(size 0.4572 0.508)
			(layers "F.Cu" "F.Mask" "F.Paste")
			(net "I3C_SPD_DDRAF_CPU0_BYPASS_SCL")
		)
	)
	(footprint ""
		(layer "F.Cu")
		(at 319.940178 -45.859954)
		(property "Reference" "C37"
			(at 0 0 0)
			(layer "F.SilkS")
			(hide yes)
			(effects
				(font
					(size 1.27 1.27)
				)
			)
		)
		(property "Value" ""
			(at 0 0 0)
			(layer "F.Fab")
			(effects
				(font
					(size 1.27 1.27)
				)
			)
		)
		(duplicate_pad_numbers_are_jumpers no)
		(fp_line
			(start -0.7874 -0.4064)
			(end 0.7874 -0.4064)
			(stroke
				(width 0.1524)
				(type default)
			)
			(layer "F.SilkS")
		)
		(fp_line
			(start -0.7874 0.4064)
			(end -0.7874 -0.4064)
			(stroke
				(width 0.1524)
				(type default)
			)
			(layer "F.SilkS")
		)
		(fp_line
			(start 0.7874 -0.4064)
			(end 0.7874 0.4064)
			(stroke
				(width 0.1524)
				(type default)
			)
			(layer "F.SilkS")
		)
		(fp_line
			(start 0.7874 0.4064)
			(end -0.7874 0.4064)
			(stroke
				(width 0.1524)
				(type default)
			)
			(layer "F.SilkS")
		)
		(fp_line
			(start -0.67945 -0.305054)
			(end -0.12065 -0.305054)
			(stroke
				(width 0.1)
				(type default)
			)
			(layer "F.Fab")
		)
		(fp_line
			(start -0.67945 0.3048)
			(end -0.67945 -0.305054)
			(stroke
				(width 0.1)
				(type default)
			)
			(layer "F.Fab")
		)
		(fp_line
			(start -0.12065 -0.305054)
			(end -0.12065 -0.2794)
			(stroke
				(width 0.1)
				(type default)
			)
			(layer "F.Fab")
		)
		(fp_line
			(start -0.12065 -0.2794)
			(end 0.12065 -0.2794)
			(stroke
				(width 0.1)
				(type default)
			)
			(layer "F.Fab")
		)
		(fp_line
			(start -0.12065 0.2794)
			(end -0.12065 0.3048)
			(stroke
				(width 0.1)
				(type default)
			)
			(layer "F.Fab")
		)
		(fp_line
			(start -0.12065 0.3048)
			(end -0.67945 0.3048)
			(stroke
				(width 0.1)
				(type default)
			)
			(layer "F.Fab")
		)
		(fp_line
			(start 0.120396 0.2794)
			(end -0.12065 0.2794)
			(stroke
				(width 0.1)
				(type default)
			)
			(layer "F.Fab")
		)
		(fp_line
			(start 0.120396 0.3048)
			(end 0.120396 0.2794)
			(stroke
				(width 0.1)
				(type default)
			)
			(layer "F.Fab")
		)
		(fp_line
			(start 0.12065 -0.3048)
			(end 0.67945 -0.3048)
			(stroke
				(width 0.1)
				(type default)
			)
			(layer "F.Fab")
		)
		(fp_line
			(start 0.12065 -0.2794)
			(end 0.12065 -0.3048)
			(stroke
				(width 0.1)
				(type default)
			)
			(layer "F.Fab")
		)
		(fp_line
			(start 0.67945 -0.3048)
			(end 0.67945 0.3048)
			(stroke
				(width 0.1)
				(type default)
			)
			(layer "F.Fab")
		)
		(fp_line
			(start 0.67945 0.3048)
			(end 0.120396 0.3048)
			(stroke
				(width 0.1)
				(type default)
			)
			(layer "F.Fab")
		)
		(pad "1" smd circle
			(at -0.40005 0)
			(size 0 0)
			(layers "F.Cu" "F.Mask" "F.Paste")
			(net "P12V_OCP_SFF_ISENSE_TIC")
		)
		(pad "2" smd circle
			(at 0.40005 0)
			(size 0 0)
			(layers "F.Cu" "F.Mask" "F.Paste")
			(net "GND")
		)
	)
)
